# BASEBOARD_FAB2 (Tioga Pass) — schematic netlist excerpt (pin names and nets, part order shuffled) for the footprints in the layout excerpt that follows; sources: Cadence DE-HDL packaged netlist, KiCad conversion of Wiwynn_Tioga_Pass_MB.brd

C9B1  CAP  10UF 16V 10% X6S  pkg 0805  page 172 : A = P5V_HDD_SATA ; B = GND
C1B11  CAP  220PF 50V 10% X7R  pkg 0402LF  page 226 : A = A_TSENSE_PVDDQ_KLM ; B = GND
R9F6  4K42R2F-GP  1%  pkg SMD-RG  page 238 : \1\ = P1V15_AUX_BMC ; \2\ = VR_P1V15_BMC_STBY_FB

(kicad_pcb
	(version 20260206)
	(generator "pcbnew")
	(generator_version "10.0")
	(general
		(thickness 1.6)
		(legacy_teardrops no)
	)
	(paper "A4")
	(title_block
		(title "Wiwynn_Tioga_Pass_MB.brd")
		(comment 1 "Tioga Pass / footprints 2276-2278 of 4770")
	)
	(layers
		(0 "F.Cu" signal "TOP")
		(4 "In1.Cu" signal "L2GND")
		(6 "In2.Cu" signal "L3")
		(8 "In3.Cu" signal "L4GND")
		(10 "In4.Cu" signal "L5")
		(12 "In5.Cu" signal "L6GND")
		(14 "In6.Cu" signal "L7VCC")
		(16 "In7.Cu" signal "L8VCC")
		(18 "In8.Cu" signal "L9GND")
		(20 "In9.Cu" signal "L10")
		(22 "In10.Cu" signal "L11GND")
		(24 "In11.Cu" signal "L12")
		(26 "In12.Cu" signal "L13GND")
		(2 "B.Cu" signal "BOTTOM")
		(9 "F.Adhes" user "F.Adhesive")
		(11 "B.Adhes" user "B.Adhesive")
		(13 "F.Paste" user "Package Geometry/Pastemask Top")
		(15 "B.Paste" user "Package Geometry/Pastemask Bottom")
		(5 "F.SilkS" user "Ref Des/Silkscreen Top")
		(7 "B.SilkS" user "Ref Des/Silkscreen Bottom")
		(1 "F.Mask" user "Board Geometry/Soldermask Top")
		(3 "B.Mask" user "Board Geometry/Soldermask Bottom")
		(17 "Dwgs.User" user "User.Drawings")
		(19 "Cmts.User" user "User.Comments")
		(21 "Eco1.User" user "User.Eco1")
		(23 "Eco2.User" user "User.Eco2")
		(25 "Edge.Cuts" user "Board Geometry/Outline")
		(27 "Margin" user)
		(31 "F.CrtYd" user "Package Geometry/Place Bound Top")
		(29 "B.CrtYd" user "Package Geometry/Place Bound Bottom")
		(35 "F.Fab" user "Ref Des/Assembly Top")
		(33 "B.Fab" user "Ref Des/Assembly Bottom")
	)
	(footprint ""
		(layer "F.Cu")
		(at 458.431392 -39.480998 90)
		(property "Reference" "R9F6"
			(at 0 0 90)
			(layer "F.SilkS")
			(hide yes)
			(effects
				(font
					(size 1.27 1.27)
				)
			)
		)
		(property "Value" "*"
			(at 0.064008 -4.108196 90)
			(unlocked yes)
			(layer "F.Fab")
			(hide yes)
			(effects
				(font
					(size 1.27 1.016)
					(thickness 0.1524)
				)
			)
		)
		(property "Device Type" "4K42R2F-GP_SMD-RG-4K42R2F-GP,6A"
			(at 0.064008 -5.632196 90)
			(unlocked yes)
			(layer "F.Fab")
			(hide yes)
			(effects
				(font
					(size 1.27 1.016)
					(thickness 0.1524)
				)
			)
		)
		(duplicate_pad_numbers_are_jumpers no)
		(fp_line
			(start 0.508 -0.9398)
			(end -0.508 -0.9398)
			(stroke
				(width 0.1524)
				(type default)
			)
			(layer "F.SilkS")
		)
		(fp_line
			(start -0.508 -0.9398)
			(end -0.508 0.9398)
			(stroke
				(width 0.1524)
				(type default)
			)
			(layer "F.SilkS")
		)
		(fp_rect
			(start -0.508 0.9398)
			(end 0.508 -0.9398)
			(stroke
				(width 0)
				(type default)
			)
			(fill no)
			(layer "F.CrtYd")
		)
		(fp_rect
			(start -0.508 0.9398)
			(end 0.508 -0.9398)
			(stroke
				(width 0)
				(type default)
			)
			(fill no)
			(layer "F.Fab")
		)
		(pad "1" smd custom
			(at 0 -0.4445 90)
			(size 0.1397 0.1397)
			(layers "F.Cu" "F.Mask" "F.Paste")
			(net "P1V15_AUX_BMC")
			(options
				(clearance outline)
				(anchor circle)
			)
			(primitives
				(gr_poly
					(pts
						(arc
							(start -0.1778 -0.2794)
							(mid -0.249642 -0.249642)
							(end -0.2794 -0.1778)
						)
						(arc
							(start -0.2794 0.1778)
							(mid -0.249642 0.249642)
							(end -0.1778 0.2794)
						)
						(arc
							(start 0.1778 0.2794)
							(mid 0.249642 0.249642)
							(end 0.2794 0.1778)
						)
						(arc
							(start 0.2794 -0.1778)
							(mid 0.249642 -0.249642)
							(end 0.1778 -0.2794)
						)
					)
					(width 0)
					(fill yes)
				)
			)
		)
		(pad "2" smd custom
			(at 0 0.4445 90)
			(size 0.1397 0.1397)
			(layers "F.Cu" "F.Mask" "F.Paste")
			(net "VR_P1V15_BMC_STBY_FB")
			(options
				(clearance outline)
				(anchor circle)
			)
			(primitives
				(gr_poly
					(pts
						(arc
							(start -0.1778 -0.2794)
							(mid -0.249642 -0.249642)
							(end -0.2794 -0.1778)
						)
						(arc
							(start -0.2794 0.1778)
							(mid -0.249642 0.249642)
							(end -0.1778 0.2794)
						)
						(arc
							(start 0.1778 0.2794)
							(mid 0.249642 0.249642)
							(end 0.2794 0.1778)
						)
						(arc
							(start 0.2794 -0.1778)
							(mid 0.249642 -0.249642)
							(end 0.1778 -0.2794)
						)
					)
					(width 0)
					(fill yes)
				)
			)
		)
	)
	(footprint ""
		(layer "F.Cu")
		(at 6.35 -126.111 90)
		(property "Reference" "C1B11"
			(at 0 0 90)
			(layer "F.SilkS")
			(hide yes)
			(effects
				(font
					(size 1.27 1.27)
				)
			)
		)
		(property "Value" ""
			(at 0 0 90)
			(layer "F.Fab")
			(effects
				(font
					(size 1.27 1.27)
				)
			)
		)
		(duplicate_pad_numbers_are_jumpers no)
		(fp_rect
			(start -0.3048 -0.1016)
			(end 0.3048 0.9906)
			(stroke
				(width 0)
				(type default)
			)
			(fill no)
			(layer "F.CrtYd")
		)
		(fp_line
			(start 0.3048 -0.1016)
			(end -0.3048 -0.1016)
			(stroke
				(width 0.1)
				(type default)
			)
			(layer "F.Fab")
		)
		(fp_line
			(start -0.3048 -0.1016)
			(end -0.3048 0.9906)
			(stroke
				(width 0.1)
				(type default)
			)
			(layer "F.Fab")
		)
		(fp_line
			(start 0.3048 0.9906)
			(end 0.3048 -0.1016)
			(stroke
				(width 0.1)
				(type default)
			)
			(layer "F.Fab")
		)
		(fp_line
			(start -0.3048 0.9906)
			(end 0.3048 0.9906)
			(stroke
				(width 0.1)
				(type default)
			)
			(layer "F.Fab")
		)
		(pad "1" smd rect
			(at 0 0 90)
			(size 0.508 0.508)
			(layers "F.Cu" "F.Mask" "F.Paste")
			(net "A_TSENSE_PVDDQ_KLM")
		)
		(pad "2" smd rect
			(at 0 0.889 90)
			(size 0.508 0.508)
			(layers "F.Cu" "F.Mask" "F.Paste")
			(net "GND")
		)
		(zone
			(layer "F.Cu")
			(hatch none 0.5)
			(connect_pads
				(clearance 0)
			)
			(min_thickness 0.25)
			(keepout
				(tracks allowed)
				(vias not_allowed)
				(pads allowed)
				(copperpour not_allowed)
				(footprints allowed)
			)
			(placement
				(enabled no)
				(sheetname "")
			)
			(fill
				(thermal_gap 0.5)
				(thermal_bridge_width 0.5)
				(island_removal_mode 0)
			)
			(polygon
				(pts
					(xy 6.604 -125.857) (xy 6.985 -125.857) (xy 6.985 -126.365) (xy 6.604 -126.365)
				)
			)
		)
		(zone
			(layer "F.Cu")
			(hatch none 0.5)
			(connect_pads
				(clearance 0)
			)
			(min_thickness 0.25)
			(keepout
				(tracks not_allowed)
				(vias allowed)
				(pads allowed)
				(copperpour not_allowed)
				(footprints allowed)
			)
			(placement
				(enabled no)
				(sheetname "")
			)
			(fill
				(thermal_gap 0.5)
				(thermal_bridge_width 0.5)
				(island_removal_mode 0)
			)
			(polygon
				(pts
					(xy 6.604 -125.857) (xy 6.985 -125.857) (xy 6.985 -126.365) (xy 6.604 -126.365)
				)
			)
		)
	)
	(footprint ""
		(layer "F.Cu")
		(at 447.4718 -129.5146 180)
		(property "Reference" "C9B1"
			(at 0 0 180)
			(layer "F.SilkS")
			(hide yes)
			(effects
				(font
					(size 1.27 1.27)
				)
			)
		)
		(property "Value" ""
			(at 0 0 180)
			(layer "F.Fab")
			(effects
				(font
					(size 1.27 1.27)
				)
			)
		)
		(duplicate_pad_numbers_are_jumpers no)
		(fp_poly
			(pts
				(xy -0.7239 -0.2159) (xy 0.7239 -0.2159) (xy 0.7239 1.9939) (xy -0.7239 1.9939)
			)
			(stroke
				(width 0)
				(type default)
			)
			(fill no)
			(layer "F.CrtYd")
		)
		(fp_line
			(start 0.7239 1.9939)
			(end 0.7239 -0.2159)
			(stroke
				(width 0.1)
				(type default)
			)
			(layer "F.Fab")
		)
		(fp_line
			(start 0.7239 -0.2159)
			(end -0.7239 -0.2159)
			(stroke
				(width 0.1)
				(type default)
			)
			(layer "F.Fab")
		)
		(fp_line
			(start -0.7239 1.9939)
			(end 0.7239 1.9939)
			(stroke
				(width 0.1)
				(type default)
			)
			(layer "F.Fab")
		)
		(fp_line
			(start -0.7239 -0.2159)
			(end -0.7239 1.9939)
			(stroke
				(width 0.1)
				(type default)
			)
			(layer "F.Fab")
		)
		(pad "1" smd rect
			(at 0 0 180)
			(size 1.27 1.016)
			(layers "F.Cu" "F.Mask" "F.Paste")
			(net "P5V_HDD_SATA")
		)
		(pad "2" smd rect
			(at 0 1.778 180)
			(size 1.27 1.016)
			(layers "F.Cu" "F.Mask" "F.Paste")
			(net "GND")
		)
		(zone
			(layer "F.Cu")
			(hatch none 0.5)
			(connect_pads
				(clearance 0)
			)
			(min_thickness 0.25)
			(keepout
				(tracks not_allowed)
				(vias allowed)
				(pads allowed)
				(copperpour not_allowed)
				(footprints allowed)
			)
			(placement
				(enabled no)
				(sheetname "")
			)
			(fill
				(thermal_gap 0.5)
				(thermal_bridge_width 0.5)
				(island_removal_mode 0)
			)
			(polygon
				(pts
					(xy 448.1068 -130.0226) (xy 446.8368 -130.0226) (xy 446.8368 -130.7846) (xy 448.1068 -130.7846)
				)
			)
		)
	)
)
